FILE_TYPE = CONNECTIVITY;
{Allegro Design Entry HDL 16.6-S040 (v16-6-112DD) 12/1/2014}
"PAGE_NUMBER" = 1;
0"NC";
1"GND\G";
2"A\I";
%"SYNONYM"
"1","(2100,2100)","0","mstr_standard","1P";
;
CDS_LIB"mstr_standard"
NEEDS_NO_SIZE"TRUE"
BODY_TYPE"PLUMBING";
"A\NWC\NAC"1;
"A\NWC\NAC"2;
%"DRAWING"
"1","(2350,1750)","0","mstr_standard","";
;
TITLE"GND"
LAST_MODIFIED"Mon Aug 22 14:31:23 2011"
ABBREV"GND";
END.
